# S9S_MB_2U (Grand Teton) — schematic netlist excerpt (pin names and nets, part order shuffled) for the footprints in the layout excerpt that follows; sources: Cadence DE-HDL packaged netlist, KiCad conversion of 03242023_DA0F0TMBIJ0_F0T_Motherboard_J_brd_V01_OCP.brd

PC553  Q_CAP  10UF 6.3V 20% X6S  pkg C0402  page 284 : A = PVCCIN_CPU1_VREF ; B = GND
R1398  Q_RES  2K 1% EMPTY  pkg 0402LF  page 219 : A = PWRGD_CPU1_LVC1_R ; B = GND

(kicad_pcb
	(version 20260206)
	(generator "pcbnew")
	(generator_version "10.0")
	(general
		(thickness 1.6)
		(legacy_teardrops no)
	)
	(paper "A4")
	(title_block
		(title "03242023_DA0F0TMBIJ0_F0T_Motherboard_J_brd_V01_OCP.brd")
		(comment 1 "Grand Teton / footprints 1254-1255 of 6105")
	)
	(layers
		(0 "F.Cu" signal "TOP")
		(4 "In1.Cu" signal "GND")
		(6 "In2.Cu" signal "IN1")
		(8 "In3.Cu" signal "GND1")
		(10 "In4.Cu" signal "IN2")
		(12 "In5.Cu" signal "GND2")
		(14 "In6.Cu" signal "IN3")
		(16 "In7.Cu" signal "GND3")
		(18 "In8.Cu" signal "VCC")
		(20 "In9.Cu" signal "VCC1")
		(22 "In10.Cu" signal "GND4")
		(24 "In11.Cu" signal "IN4")
		(26 "In12.Cu" signal "GND5")
		(28 "In13.Cu" signal "IN5")
		(30 "In14.Cu" signal "GND6")
		(32 "In15.Cu" signal "IN6")
		(34 "In16.Cu" signal "GND7")
		(2 "B.Cu" signal "BOTTOM")
		(9 "F.Adhes" user "F.Adhesive")
		(11 "B.Adhes" user "B.Adhesive")
		(13 "F.Paste" user "Package Geometry/Pastemask Top")
		(15 "B.Paste" user "Package Geometry/Pastemask Bottom")
		(5 "F.SilkS" user "Ref Des/Silkscreen Top")
		(7 "B.SilkS" user "Ref Des/Silkscreen Bottom")
		(1 "F.Mask" user "Board Geometry/Soldermask Top")
		(3 "B.Mask" user "Board Geometry/Soldermask Bottom")
		(17 "Dwgs.User" user "User.Drawings")
		(19 "Cmts.User" user "User.Comments")
		(21 "Eco1.User" user "User.Eco1")
		(23 "Eco2.User" user "User.Eco2")
		(25 "Edge.Cuts" user "Board Geometry/Outline")
		(27 "Margin" user)
		(31 "F.CrtYd" user "Package Geometry/Place Bound Top")
		(29 "B.CrtYd" user "Package Geometry/Place Bound Bottom")
		(35 "F.Fab" user "Ref Des/Assembly Top")
		(33 "B.Fab" user "Ref Des/Assembly Bottom")
	)
	(footprint ""
		(layer "F.Cu")
		(at 114.243612 -365.158274 90)
		(property "Reference" "PC553"
			(at 0 0 90)
			(layer "F.SilkS")
			(hide yes)
			(effects
				(font
					(size 1.27 1.27)
				)
			)
		)
		(property "Value" ""
			(at 0 0 90)
			(layer "F.Fab")
			(effects
				(font
					(size 1.27 1.27)
				)
			)
		)
		(duplicate_pad_numbers_are_jumpers no)
		(fp_line
			(start 0.7874 -0.4064)
			(end 0.7874 0.4064)
			(stroke
				(width 0.1524)
				(type default)
			)
			(layer "F.SilkS")
		)
		(fp_line
			(start -0.7874 -0.4064)
			(end 0.7874 -0.4064)
			(stroke
				(width 0.1524)
				(type default)
			)
			(layer "F.SilkS")
		)
		(fp_line
			(start 0.7874 0.4064)
			(end -0.7874 0.4064)
			(stroke
				(width 0.1524)
				(type default)
			)
			(layer "F.SilkS")
		)
		(fp_line
			(start -0.7874 0.4064)
			(end -0.7874 -0.4064)
			(stroke
				(width 0.1524)
				(type default)
			)
			(layer "F.SilkS")
		)
		(fp_line
			(start -0.12065 -0.305054)
			(end -0.12065 -0.2794)
			(stroke
				(width 0.1)
				(type default)
			)
			(layer "F.Fab")
		)
		(fp_line
			(start -0.67945 -0.305054)
			(end -0.12065 -0.305054)
			(stroke
				(width 0.1)
				(type default)
			)
			(layer "F.Fab")
		)
		(fp_line
			(start 0.67945 -0.3048)
			(end 0.67945 0.3048)
			(stroke
				(width 0.1)
				(type default)
			)
			(layer "F.Fab")
		)
		(fp_line
			(start 0.12065 -0.3048)
			(end 0.67945 -0.3048)
			(stroke
				(width 0.1)
				(type default)
			)
			(layer "F.Fab")
		)
		(fp_line
			(start 0.12065 -0.2794)
			(end 0.12065 -0.3048)
			(stroke
				(width 0.1)
				(type default)
			)
			(layer "F.Fab")
		)
		(fp_line
			(start -0.12065 -0.2794)
			(end 0.12065 -0.2794)
			(stroke
				(width 0.1)
				(type default)
			)
			(layer "F.Fab")
		)
		(fp_line
			(start 0.120396 0.2794)
			(end -0.12065 0.2794)
			(stroke
				(width 0.1)
				(type default)
			)
			(layer "F.Fab")
		)
		(fp_line
			(start -0.12065 0.2794)
			(end -0.12065 0.3048)
			(stroke
				(width 0.1)
				(type default)
			)
			(layer "F.Fab")
		)
		(fp_line
			(start 0.67945 0.3048)
			(end 0.120396 0.3048)
			(stroke
				(width 0.1)
				(type default)
			)
			(layer "F.Fab")
		)
		(fp_line
			(start 0.120396 0.3048)
			(end 0.120396 0.2794)
			(stroke
				(width 0.1)
				(type default)
			)
			(layer "F.Fab")
		)
		(fp_line
			(start -0.12065 0.3048)
			(end -0.67945 0.3048)
			(stroke
				(width 0.1)
				(type default)
			)
			(layer "F.Fab")
		)
		(fp_line
			(start -0.67945 0.3048)
			(end -0.67945 -0.305054)
			(stroke
				(width 0.1)
				(type default)
			)
			(layer "F.Fab")
		)
		(pad "1" smd circle
			(at -0.40005 0 90)
			(size 0 0)
			(layers "F.Cu" "F.Mask" "F.Paste")
			(net "PVCCIN_CPU1_VREF")
		)
		(pad "2" smd circle
			(at 0.40005 0 90)
			(size 0 0)
			(layers "F.Cu" "F.Mask" "F.Paste")
			(net "GND")
		)
	)
	(footprint ""
		(layer "F.Cu")
		(at 184.96788 -97.119948 -90)
		(property "Reference" "R1398"
			(at 0 0 270)
			(layer "F.SilkS")
			(hide yes)
			(effects
				(font
					(size 1.27 1.27)
				)
			)
		)
		(property "Value" ""
			(at 0 0 270)
			(layer "F.Fab")
			(effects
				(font
					(size 1.27 1.27)
				)
			)
		)
		(duplicate_pad_numbers_are_jumpers no)
		(fp_line
			(start -0.7874 0.4064)
			(end -0.7874 -0.4064)
			(stroke
				(width 0.1524)
				(type default)
			)
			(layer "F.SilkS")
		)
		(fp_line
			(start 0.7874 0.4064)
			(end -0.7874 0.4064)
			(stroke
				(width 0.1524)
				(type default)
			)
			(layer "F.SilkS")
		)
		(fp_line
			(start -0.7874 -0.4064)
			(end 0.7874 -0.4064)
			(stroke
				(width 0.1524)
				(type default)
			)
			(layer "F.SilkS")
		)
		(fp_line
			(start 0.7874 -0.4064)
			(end 0.7874 0.4064)
			(stroke
				(width 0.1524)
				(type default)
			)
			(layer "F.SilkS")
		)
		(fp_line
			(start -0.67945 0.3048)
			(end -0.67945 -0.305054)
			(stroke
				(width 0.1)
				(type default)
			)
			(layer "F.Fab")
		)
		(fp_line
			(start -0.12065 0.3048)
			(end -0.67945 0.3048)
			(stroke
				(width 0.1)
				(type default)
			)
			(layer "F.Fab")
		)
		(fp_line
			(start 0.120396 0.3048)
			(end 0.120396 0.2794)
			(stroke
				(width 0.1)
				(type default)
			)
			(layer "F.Fab")
		)
		(fp_line
			(start 0.67945 0.3048)
			(end 0.120396 0.3048)
			(stroke
				(width 0.1)
				(type default)
			)
			(layer "F.Fab")
		)
		(fp_line
			(start -0.12065 0.2794)
			(end -0.12065 0.3048)
			(stroke
				(width 0.1)
				(type default)
			)
			(layer "F.Fab")
		)
		(fp_line
			(start 0.120396 0.2794)
			(end -0.12065 0.2794)
			(stroke
				(width 0.1)
				(type default)
			)
			(layer "F.Fab")
		)
		(fp_line
			(start -0.12065 -0.2794)
			(end 0.12065 -0.2794)
			(stroke
				(width 0.1)
				(type default)
			)
			(layer "F.Fab")
		)
		(fp_line
			(start 0.12065 -0.2794)
			(end 0.12065 -0.3048)
			(stroke
				(width 0.1)
				(type default)
			)
			(layer "F.Fab")
		)
		(fp_line
			(start 0.12065 -0.3048)
			(end 0.67945 -0.3048)
			(stroke
				(width 0.1)
				(type default)
			)
			(layer "F.Fab")
		)
		(fp_line
			(start 0.67945 -0.3048)
			(end 0.67945 0.3048)
			(stroke
				(width 0.1)
				(type default)
			)
			(layer "F.Fab")
		)
		(fp_line
			(start -0.67945 -0.305054)
			(end -0.12065 -0.305054)
			(stroke
				(width 0.1)
				(type default)
			)
			(layer "F.Fab")
		)
		(fp_line
			(start -0.12065 -0.305054)
			(end -0.12065 -0.2794)
			(stroke
				(width 0.1)
				(type default)
			)
			(layer "F.Fab")
		)
		(pad "1" smd circle
			(at -0.40005 0 270)
			(size 0 0)
			(layers "F.Cu" "F.Mask" "F.Paste")
			(net "PWRGD_CPU1_LVC1_R")
		)
		(pad "2" smd circle
			(at 0.40005 0 270)
			(size 0 0)
			(layers "F.Cu" "F.Mask" "F.Paste")
			(net "GND")
		)
	)
)
